# Barreleye-G2_Tri-mode BPX24-DVT-X01-SKU-BOM-X07-20171222_Final.xls.xlsx — Component Qual Tracker (bom)
|  |  |  |  |  |  |  |  | Part to be included on following build: |  |  |  |  |  |
| Item No. | Part Group | Single/Sole/Multi | Item Description | ODM P/N | Customer PN | Vendor | Vendor P/N | X00 Build | X01 Build | X02 Build | Qual Build | Qualification Target Date | Qualification Complete Date |
|  | VR Controllers |  |  |  |  | Vendor #1 |  |  |  |  |  |  |  |
|  |  |  |  |  |  | Vendor #2 |  |  |  |  |  |  |  |
|  | FETS |  |  |  |  | Vendor #1 |  |  |  |  |  |  |  |
|  |  |  |  |  |  | Vendor #2 |  |  |  |  |  |  |  |
|  | INDUCTORS |  |  |  |  | Vendor #1 |  |  |  |  |  |  |  |
|  |  |  |  |  |  | Vendor #2 |  |  |  |  |  |  |  |
|  | VREG CAPS |  |  |  |  | Vendor #1 |  |  |  |  |  |  |  |
|  |  |  |  |  |  | Vendor #2 |  |  |  |  |  |  |  |
|  | CRYSTALS |  |  |  |  | Vendor #1 |  |  |  |  |  |  |  |
|  |  |  |  |  |  | Vendor #2 |  |  |  |  |  |  |  |
|  | CONNECTORS |  |  |  |  | Vendor #1 |  |  |  |  |  |  |  |
|  |  |  |  |  |  | Vendor #2 |  |  |  |  |  |  |  |
|  | IC'S |  |  |  |  | Vendor #1 |  |  |  |  |  |  |  |
|  |  |  |  |  |  | Vendor #2 |  |  |  |  |  |  |  |
|  | MISC. |  |  |  |  | Vendor #1 |  |  |  |  |  |  |  |
|  | (HEATSINKS) |  |  |  |  | Vendor #2 |  |  |  |  |  |  |  |
